(kicad_pcb
	(version 20260206)
	(generator "pcbnew")
	(generator_version "10.0")
	(general
		(thickness 1.6)
		(legacy_teardrops no)
	)
	(paper "A4")
	(title_block
		(title "01162023_DA0F0TEBIF0_F0T_Expander_BD_F_brd_V02_OCP.brd")
		(comment 1 "Grand Teton / footprints 3081-3086 of 9728")
	)
	(layers
		(0 "F.Cu" signal "TOP")
		(4 "In1.Cu" signal "GND")
		(6 "In2.Cu" signal "VCC")
		(8 "In3.Cu" signal "VCC1")
		(10 "In4.Cu" signal "GND1")
		(12 "In5.Cu" signal "IN1")
		(14 "In6.Cu" signal "GND2")
		(16 "In7.Cu" signal "IN2")
		(18 "In8.Cu" signal "GND3")
		(20 "In9.Cu" signal "IN3")
		(22 "In10.Cu" signal "GND4")
		(24 "In11.Cu" signal "IN4")
		(26 "In12.Cu" signal "GND5")
		(28 "In13.Cu" signal "IN5")
		(30 "In14.Cu" signal "GND6")
		(32 "In15.Cu" signal "IN6")
		(34 "In16.Cu" signal "GND7")
		(2 "B.Cu" signal "BOTTOM")
		(9 "F.Adhes" user "F.Adhesive")
		(11 "B.Adhes" user "B.Adhesive")
		(13 "F.Paste" user "Package Geometry/Pastemask Top")
		(15 "B.Paste" user "Package Geometry/Pastemask Bottom")
		(5 "F.SilkS" user "Ref Des/Silkscreen Top")
		(7 "B.SilkS" user "Ref Des/Silkscreen Bottom")
		(1 "F.Mask" user "Board Geometry/Soldermask Top")
		(3 "B.Mask" user "Board Geometry/Soldermask Bottom")
		(17 "Dwgs.User" user "User.Drawings")
		(19 "Cmts.User" user "User.Comments")
		(21 "Eco1.User" user "User.Eco1")
		(23 "Eco2.User" user "User.Eco2")
		(25 "Edge.Cuts" user "Board Geometry/Outline")
		(27 "Margin" user)
		(31 "F.CrtYd" user "Package Geometry/Place Bound Top")
		(29 "B.CrtYd" user "Package Geometry/Place Bound Bottom")
		(35 "F.Fab" user "Ref Des/Assembly Top")
		(33 "B.Fab" user "Ref Des/Assembly Bottom")
	)
	(footprint ""
		(layer "F.Cu")
		(at 336.042 -164.973)
		(property "Reference" "R4733"
			(at 0 0 0)
			(layer "F.SilkS")
			(hide yes)
			(effects
				(font
					(size 1.27 1.27)
				)
			)
		)
		(property "Value" ""
			(at 0 0 0)
			(layer "F.Fab")
			(effects
				(font
					(size 1.27 1.27)
				)
			)
		)
		(duplicate_pad_numbers_are_jumpers no)
		(fp_line
			(start -0.7874 -0.4064)
			(end 0.7874 -0.4064)
			(stroke
				(width 0.1524)
				(type default)
			)
			(layer "F.SilkS")
		)
		(fp_line
			(start -0.7874 0.4064)
			(end -0.7874 -0.4064)
			(stroke
				(width 0.1524)
				(type default)
			)
			(layer "F.SilkS")
		)
		(fp_line
			(start 0.7874 -0.4064)
			(end 0.7874 0.4064)
			(stroke
				(width 0.1524)
				(type default)
			)
			(layer "F.SilkS")
		)
		(fp_line
			(start 0.7874 0.4064)
			(end -0.7874 0.4064)
			(stroke
				(width 0.1524)
				(type default)
			)
			(layer "F.SilkS")
		)
		(fp_line
			(start -0.67945 -0.305054)
			(end -0.12065 -0.305054)
			(stroke
				(width 0.1)
				(type default)
			)
			(layer "F.Fab")
		)
		(fp_line
			(start -0.67945 0.3048)
			(end -0.67945 -0.305054)
			(stroke
				(width 0.1)
				(type default)
			)
			(layer "F.Fab")
		)
		(fp_line
			(start -0.12065 -0.305054)
			(end -0.12065 -0.2794)
			(stroke
				(width 0.1)
				(type default)
			)
			(layer "F.Fab")
		)
		(fp_line
			(start -0.12065 -0.2794)
			(end 0.12065 -0.2794)
			(stroke
				(width 0.1)
				(type default)
			)
			(layer "F.Fab")
		)
		(fp_line
			(start -0.12065 0.2794)
			(end -0.12065 0.3048)
			(stroke
				(width 0.1)
				(type default)
			)
			(layer "F.Fab")
		)
		(fp_line
			(start -0.12065 0.3048)
			(end -0.67945 0.3048)
			(stroke
				(width 0.1)
				(type default)
			)
			(layer "F.Fab")
		)
		(fp_line
			(start 0.120396 0.2794)
			(end -0.12065 0.2794)
			(stroke
				(width 0.1)
				(type default)
			)
			(layer "F.Fab")
		)
		(fp_line
			(start 0.120396 0.3048)
			(end 0.120396 0.2794)
			(stroke
				(width 0.1)
				(type default)
			)
			(layer "F.Fab")
		)
		(fp_line
			(start 0.12065 -0.3048)
			(end 0.67945 -0.3048)
			(stroke
				(width 0.1)
				(type default)
			)
			(layer "F.Fab")
		)
		(fp_line
			(start 0.12065 -0.2794)
			(end 0.12065 -0.3048)
			(stroke
				(width 0.1)
				(type default)
			)
			(layer "F.Fab")
		)
		(fp_line
			(start 0.67945 -0.3048)
			(end 0.67945 0.3048)
			(stroke
				(width 0.1)
				(type default)
			)
			(layer "F.Fab")
		)
		(fp_line
			(start 0.67945 0.3048)
			(end 0.120396 0.3048)
			(stroke
				(width 0.1)
				(type default)
			)
			(layer "F.Fab")
		)
		(pad "1" smd circle
			(at -0.40005 0)
			(size 0 0)
			(layers "F.Cu" "F.Mask" "F.Paste")
			(net "P3V3_AUX")
		)
		(pad "2" smd circle
			(at 0.40005 0)
			(size 0 0)
			(layers "F.Cu" "F.Mask" "F.Paste")
			(net "RST_PEX_SSD11_PERST_R_N")
		)
	)
	(footprint ""
		(layer "F.Cu")
		(at 394.97508 -56.977534 180)
		(property "Reference" "PC424"
			(at 0 0 180)
			(layer "F.SilkS")
			(hide yes)
			(effects
				(font
					(size 1.27 1.27)
				)
			)
		)
		(property "Value" ""
			(at 0 0 180)
			(layer "F.Fab")
			(effects
				(font
					(size 1.27 1.27)
				)
			)
		)
		(duplicate_pad_numbers_are_jumpers no)
		(fp_line
			(start 0.7874 0.4064)
			(end -0.7874 0.4064)
			(stroke
				(width 0.1524)
				(type default)
			)
			(layer "F.SilkS")
		)
		(fp_line
			(start 0.7874 -0.4064)
			(end 0.7874 0.4064)
			(stroke
				(width 0.1524)
				(type default)
			)
			(layer "F.SilkS")
		)
		(fp_line
			(start -0.7874 0.4064)
			(end -0.7874 -0.4064)
			(stroke
				(width 0.1524)
				(type default)
			)
			(layer "F.SilkS")
		)
		(fp_line
			(start -0.7874 -0.4064)
			(end 0.7874 -0.4064)
			(stroke
				(width 0.1524)
				(type default)
			)
			(layer "F.SilkS")
		)
		(fp_line
			(start 0.67945 0.3048)
			(end 0.120396 0.3048)
			(stroke
				(width 0.1)
				(type default)
			)
			(layer "F.Fab")
		)
		(fp_line
			(start 0.67945 -0.3048)
			(end 0.67945 0.3048)
			(stroke
				(width 0.1)
				(type default)
			)
			(layer "F.Fab")
		)
		(fp_line
			(start 0.12065 -0.2794)
			(end 0.12065 -0.3048)
			(stroke
				(width 0.1)
				(type default)
			)
			(layer "F.Fab")
		)
		(fp_line
			(start 0.12065 -0.3048)
			(end 0.67945 -0.3048)
			(stroke
				(width 0.1)
				(type default)
			)
			(layer "F.Fab")
		)
		(fp_line
			(start 0.120396 0.3048)
			(end 0.120396 0.2794)
			(stroke
				(width 0.1)
				(type default)
			)
			(layer "F.Fab")
		)
		(fp_line
			(start 0.120396 0.2794)
			(end -0.12065 0.2794)
			(stroke
				(width 0.1)
				(type default)
			)
			(layer "F.Fab")
		)
		(fp_line
			(start -0.12065 0.3048)
			(end -0.67945 0.3048)
			(stroke
				(width 0.1)
				(type default)
			)
			(layer "F.Fab")
		)
		(fp_line
			(start -0.12065 0.2794)
			(end -0.12065 0.3048)
			(stroke
				(width 0.1)
				(type default)
			)
			(layer "F.Fab")
		)
		(fp_line
			(start -0.12065 -0.2794)
			(end 0.12065 -0.2794)
			(stroke
				(width 0.1)
				(type default)
			)
			(layer "F.Fab")
		)
		(fp_line
			(start -0.12065 -0.305054)
			(end -0.12065 -0.2794)
			(stroke
				(width 0.1)
				(type default)
			)
			(layer "F.Fab")
		)
		(fp_line
			(start -0.67945 0.3048)
			(end -0.67945 -0.305054)
			(stroke
				(width 0.1)
				(type default)
			)
			(layer "F.Fab")
		)
		(fp_line
			(start -0.67945 -0.305054)
			(end -0.12065 -0.305054)
			(stroke
				(width 0.1)
				(type default)
			)
			(layer "F.Fab")
		)
		(pad "1" smd circle
			(at -0.40005 0 180)
			(size 0 0)
			(layers "F.Cu" "F.Mask" "F.Paste")
			(net "P12V_AUX")
		)
		(pad "2" smd circle
			(at 0.40005 0 180)
			(size 0 0)
			(layers "F.Cu" "F.Mask" "F.Paste")
			(net "GND")
		)
	)
	(footprint ""
		(layer "F.Cu")
		(at 361.188 -180.086 180)
		(property "Reference" "R4717"
			(at 0 0 180)
			(layer "F.SilkS")
			(hide yes)
			(effects
				(font
					(size 1.27 1.27)
				)
			)
		)
		(property "Value" ""
			(at 0 0 180)
			(layer "F.Fab")
			(effects
				(font
					(size 1.27 1.27)
				)
			)
		)
		(duplicate_pad_numbers_are_jumpers no)
		(fp_line
			(start 0.7874 0.4064)
			(end -0.7874 0.4064)
			(stroke
				(width 0.1524)
				(type default)
			)
			(layer "F.SilkS")
		)
		(fp_line
			(start 0.7874 -0.4064)
			(end 0.7874 0.4064)
			(stroke
				(width 0.1524)
				(type default)
			)
			(layer "F.SilkS")
		)
		(fp_line
			(start -0.7874 0.4064)
			(end -0.7874 -0.4064)
			(stroke
				(width 0.1524)
				(type default)
			)
			(layer "F.SilkS")
		)
		(fp_line
			(start -0.7874 -0.4064)
			(end 0.7874 -0.4064)
			(stroke
				(width 0.1524)
				(type default)
			)
			(layer "F.SilkS")
		)
		(fp_line
			(start 0.67945 0.3048)
			(end 0.120396 0.3048)
			(stroke
				(width 0.1)
				(type default)
			)
			(layer "F.Fab")
		)
		(fp_line
			(start 0.67945 -0.3048)
			(end 0.67945 0.3048)
			(stroke
				(width 0.1)
				(type default)
			)
			(layer "F.Fab")
		)
		(fp_line
			(start 0.12065 -0.2794)
			(end 0.12065 -0.3048)
			(stroke
				(width 0.1)
				(type default)
			)
			(layer "F.Fab")
		)
		(fp_line
			(start 0.12065 -0.3048)
			(end 0.67945 -0.3048)
			(stroke
				(width 0.1)
				(type default)
			)
			(layer "F.Fab")
		)
		(fp_line
			(start 0.120396 0.3048)
			(end 0.120396 0.2794)
			(stroke
				(width 0.1)
				(type default)
			)
			(layer "F.Fab")
		)
		(fp_line
			(start 0.120396 0.2794)
			(end -0.12065 0.2794)
			(stroke
				(width 0.1)
				(type default)
			)
			(layer "F.Fab")
		)
		(fp_line
			(start -0.12065 0.3048)
			(end -0.67945 0.3048)
			(stroke
				(width 0.1)
				(type default)
			)
			(layer "F.Fab")
		)
		(fp_line
			(start -0.12065 0.2794)
			(end -0.12065 0.3048)
			(stroke
				(width 0.1)
				(type default)
			)
			(layer "F.Fab")
		)
		(fp_line
			(start -0.12065 -0.2794)
			(end 0.12065 -0.2794)
			(stroke
				(width 0.1)
				(type default)
			)
			(layer "F.Fab")
		)
		(fp_line
			(start -0.12065 -0.305054)
			(end -0.12065 -0.2794)
			(stroke
				(width 0.1)
				(type default)
			)
			(layer "F.Fab")
		)
		(fp_line
			(start -0.67945 0.3048)
			(end -0.67945 -0.305054)
			(stroke
				(width 0.1)
				(type default)
			)
			(layer "F.Fab")
		)
		(fp_line
			(start -0.67945 -0.305054)
			(end -0.12065 -0.305054)
			(stroke
				(width 0.1)
				(type default)
			)
			(layer "F.Fab")
		)
		(pad "1" smd circle
			(at -0.40005 0 180)
			(size 0 0)
			(layers "F.Cu" "F.Mask" "F.Paste")
			(net "GND")
		)
		(pad "2" smd circle
			(at 0.40005 0 180)
			(size 0 0)
			(layers "F.Cu" "F.Mask" "F.Paste")
			(net "PCA9555_1_PEX1_A2")
		)
	)
	(footprint ""
		(layer "F.Cu")
		(at 7.613396 -137.344404 180)
		(property "Reference" "PR193"
			(at 0 0 180)
			(layer "F.SilkS")
			(hide yes)
			(effects
				(font
					(size 1.27 1.27)
				)
			)
		)
		(property "Value" ""
			(at 0 0 180)
			(layer "F.Fab")
			(effects
				(font
					(size 1.27 1.27)
				)
			)
		)
		(duplicate_pad_numbers_are_jumpers no)
		(fp_line
			(start 0.7874 0.4064)
			(end -0.7874 0.4064)
			(stroke
				(width 0.1524)
				(type default)
			)
			(layer "F.SilkS")
		)
		(fp_line
			(start 0.7874 -0.4064)
			(end 0.7874 0.4064)
			(stroke
				(width 0.1524)
				(type default)
			)
			(layer "F.SilkS")
		)
		(fp_line
			(start -0.7874 0.4064)
			(end -0.7874 -0.4064)
			(stroke
				(width 0.1524)
				(type default)
			)
			(layer "F.SilkS")
		)
		(fp_line
			(start -0.7874 -0.4064)
			(end 0.7874 -0.4064)
			(stroke
				(width 0.1524)
				(type default)
			)
			(layer "F.SilkS")
		)
		(fp_line
			(start 0.67945 0.3048)
			(end 0.120396 0.3048)
			(stroke
				(width 0.1)
				(type default)
			)
			(layer "F.Fab")
		)
		(fp_line
			(start 0.67945 -0.3048)
			(end 0.67945 0.3048)
			(stroke
				(width 0.1)
				(type default)
			)
			(layer "F.Fab")
		)
		(fp_line
			(start 0.12065 -0.2794)
			(end 0.12065 -0.3048)
			(stroke
				(width 0.1)
				(type default)
			)
			(layer "F.Fab")
		)
		(fp_line
			(start 0.12065 -0.3048)
			(end 0.67945 -0.3048)
			(stroke
				(width 0.1)
				(type default)
			)
			(layer "F.Fab")
		)
		(fp_line
			(start 0.120396 0.3048)
			(end 0.120396 0.2794)
			(stroke
				(width 0.1)
				(type default)
			)
			(layer "F.Fab")
		)
		(fp_line
			(start 0.120396 0.2794)
			(end -0.12065 0.2794)
			(stroke
				(width 0.1)
				(type default)
			)
			(layer "F.Fab")
		)
		(fp_line
			(start -0.12065 0.3048)
			(end -0.67945 0.3048)
			(stroke
				(width 0.1)
				(type default)
			)
			(layer "F.Fab")
		)
		(fp_line
			(start -0.12065 0.2794)
			(end -0.12065 0.3048)
			(stroke
				(width 0.1)
				(type default)
			)
			(layer "F.Fab")
		)
		(fp_line
			(start -0.12065 -0.2794)
			(end 0.12065 -0.2794)
			(stroke
				(width 0.1)
				(type default)
			)
			(layer "F.Fab")
		)
		(fp_line
			(start -0.12065 -0.305054)
			(end -0.12065 -0.2794)
			(stroke
				(width 0.1)
				(type default)
			)
			(layer "F.Fab")
		)
		(fp_line
			(start -0.67945 0.3048)
			(end -0.67945 -0.305054)
			(stroke
				(width 0.1)
				(type default)
			)
			(layer "F.Fab")
		)
		(fp_line
			(start -0.67945 -0.305054)
			(end -0.12065 -0.305054)
			(stroke
				(width 0.1)
				(type default)
			)
			(layer "F.Fab")
		)
		(pad "1" smd circle
			(at -0.40005 0 180)
			(size 0 0)
			(layers "F.Cu" "F.Mask" "F.Paste")
			(net "P12V_NIC0_OCP")
		)
		(pad "2" smd circle
			(at 0.40005 0 180)
			(size 0 0)
			(layers "F.Cu" "F.Mask" "F.Paste")
			(net "GND")
		)
	)
	(footprint ""
		(layer "F.Cu")
		(at 287.075118 -64.102234 180)
		(property "Reference" "PR7085"
			(at 0 0 180)
			(layer "F.SilkS")
			(hide yes)
			(effects
				(font
					(size 1.27 1.27)
				)
			)
		)
		(property "Value" ""
			(at 0 0 180)
			(layer "F.Fab")
			(effects
				(font
					(size 1.27 1.27)
				)
			)
		)
		(duplicate_pad_numbers_are_jumpers no)
		(fp_line
			(start 0.7874 0.4064)
			(end -0.7874 0.4064)
			(stroke
				(width 0.1524)
				(type default)
			)
			(layer "F.SilkS")
		)
		(fp_line
			(start 0.7874 -0.4064)
			(end 0.7874 0.4064)
			(stroke
				(width 0.1524)
				(type default)
			)
			(layer "F.SilkS")
		)
		(fp_line
			(start -0.7874 0.4064)
			(end -0.7874 -0.4064)
			(stroke
				(width 0.1524)
				(type default)
			)
			(layer "F.SilkS")
		)
		(fp_line
			(start -0.7874 -0.4064)
			(end 0.7874 -0.4064)
			(stroke
				(width 0.1524)
				(type default)
			)
			(layer "F.SilkS")
		)
		(fp_line
			(start 0.67945 0.3048)
			(end 0.120396 0.3048)
			(stroke
				(width 0.1)
				(type default)
			)
			(layer "F.Fab")
		)
		(fp_line
			(start 0.67945 -0.3048)
			(end 0.67945 0.3048)
			(stroke
				(width 0.1)
				(type default)
			)
			(layer "F.Fab")
		)
		(fp_line
			(start 0.12065 -0.2794)
			(end 0.12065 -0.3048)
			(stroke
				(width 0.1)
				(type default)
			)
			(layer "F.Fab")
		)
		(fp_line
			(start 0.12065 -0.3048)
			(end 0.67945 -0.3048)
			(stroke
				(width 0.1)
				(type default)
			)
			(layer "F.Fab")
		)
		(fp_line
			(start 0.120396 0.3048)
			(end 0.120396 0.2794)
			(stroke
				(width 0.1)
				(type default)
			)
			(layer "F.Fab")
		)
		(fp_line
			(start 0.120396 0.2794)
			(end -0.12065 0.2794)
			(stroke
				(width 0.1)
				(type default)
			)
			(layer "F.Fab")
		)
		(fp_line
			(start -0.12065 0.3048)
			(end -0.67945 0.3048)
			(stroke
				(width 0.1)
				(type default)
			)
			(layer "F.Fab")
		)
		(fp_line
			(start -0.12065 0.2794)
			(end -0.12065 0.3048)
			(stroke
				(width 0.1)
				(type default)
			)
			(layer "F.Fab")
		)
		(fp_line
			(start -0.12065 -0.2794)
			(end 0.12065 -0.2794)
			(stroke
				(width 0.1)
				(type default)
			)
			(layer "F.Fab")
		)
		(fp_line
			(start -0.12065 -0.305054)
			(end -0.12065 -0.2794)
			(stroke
				(width 0.1)
				(type default)
			)
			(layer "F.Fab")
		)
		(fp_line
			(start -0.67945 0.3048)
			(end -0.67945 -0.305054)
			(stroke
				(width 0.1)
				(type default)
			)
			(layer "F.Fab")
		)
		(fp_line
			(start -0.67945 -0.305054)
			(end -0.12065 -0.305054)
			(stroke
				(width 0.1)
				(type default)
			)
			(layer "F.Fab")
		)
		(pad "1" smd circle
			(at -0.40005 0 180)
			(size 0 0)
			(layers "F.Cu" "F.Mask" "F.Paste")
			(net "P12V_SSD10_PG_G1")
		)
		(pad "2" smd circle
			(at 0.40005 0 180)
			(size 0 0)
			(layers "F.Cu" "F.Mask" "F.Paste")
			(net "GND")
		)
	)
	(footprint ""
		(layer "F.Cu")
		(at 244.264434 -250.759722 -90)
		(property "Reference" "R6226"
			(at 0 0 270)
			(layer "F.SilkS")
			(hide yes)
			(effects
				(font
					(size 1.27 1.27)
				)
			)
		)
		(property "Value" ""
			(at 0 0 270)
			(layer "F.Fab")
			(effects
				(font
					(size 1.27 1.27)
				)
			)
		)
		(duplicate_pad_numbers_are_jumpers no)
		(fp_line
			(start -0.7874 0.4064)
			(end -0.7874 -0.4064)
			(stroke
				(width 0.1524)
				(type default)
			)
			(layer "F.SilkS")
		)
		(fp_line
			(start 0.7874 0.4064)
			(end -0.7874 0.4064)
			(stroke
				(width 0.1524)
				(type default)
			)
			(layer "F.SilkS")
		)
		(fp_line
			(start -0.7874 -0.4064)
			(end 0.7874 -0.4064)
			(stroke
				(width 0.1524)
				(type default)
			)
			(layer "F.SilkS")
		)
		(fp_line
			(start 0.7874 -0.4064)
			(end 0.7874 0.4064)
			(stroke
				(width 0.1524)
				(type default)
			)
			(layer "F.SilkS")
		)
		(fp_line
			(start -0.67945 0.3048)
			(end -0.67945 -0.305054)
			(stroke
				(width 0.1)
				(type default)
			)
			(layer "F.Fab")
		)
		(fp_line
			(start -0.12065 0.3048)
			(end -0.67945 0.3048)
			(stroke
				(width 0.1)
				(type default)
			)
			(layer "F.Fab")
		)
		(fp_line
			(start 0.120396 0.3048)
			(end 0.120396 0.2794)
			(stroke
				(width 0.1)
				(type default)
			)
			(layer "F.Fab")
		)
		(fp_line
			(start 0.67945 0.3048)
			(end 0.120396 0.3048)
			(stroke
				(width 0.1)
				(type default)
			)
			(layer "F.Fab")
		)
		(fp_line
			(start -0.12065 0.2794)
			(end -0.12065 0.3048)
			(stroke
				(width 0.1)
				(type default)
			)
			(layer "F.Fab")
		)
		(fp_line
			(start 0.120396 0.2794)
			(end -0.12065 0.2794)
			(stroke
				(width 0.1)
				(type default)
			)
			(layer "F.Fab")
		)
		(fp_line
			(start -0.12065 -0.2794)
			(end 0.12065 -0.2794)
			(stroke
				(width 0.1)
				(type default)
			)
			(layer "F.Fab")
		)
		(fp_line
			(start 0.12065 -0.2794)
			(end 0.12065 -0.3048)
			(stroke
				(width 0.1)
				(type default)
			)
			(layer "F.Fab")
		)
		(fp_line
			(start 0.12065 -0.3048)
			(end 0.67945 -0.3048)
			(stroke
				(width 0.1)
				(type default)
			)
			(layer "F.Fab")
		)
		(fp_line
			(start 0.67945 -0.3048)
			(end 0.67945 0.3048)
			(stroke
				(width 0.1)
				(type default)
			)
			(layer "F.Fab")
		)
		(fp_line
			(start -0.67945 -0.305054)
			(end -0.12065 -0.305054)
			(stroke
				(width 0.1)
				(type default)
			)
			(layer "F.Fab")
		)
		(fp_line
			(start -0.12065 -0.305054)
			(end -0.12065 -0.2794)
			(stroke
				(width 0.1)
				(type default)
			)
			(layer "F.Fab")
		)
		(pad "1" smd circle
			(at -0.40005 0 270)
			(size 0 0)
			(layers "F.Cu" "F.Mask" "F.Paste")
			(net "P3V3_AUX")
		)
		(pad "2" smd circle
			(at 0.40005 0 270)
			(size 0 0)
			(layers "F.Cu" "F.Mask" "F.Paste")
			(net "BIC_RECOVER_IOEXP_A1")
		)
	)
)
